# S9S_MB_2U (Grand Teton) — schematic netlist excerpt (pin names and nets, part order shuffled) for the footprints in the layout excerpt that follows; sources: Cadence DE-HDL packaged netlist, KiCad conversion of 03242023_DA0F0TMBIJ0_F0T_Motherboard_J_brd_V01_OCP.brd

R3434  Q_RES  4.7K 5% CHIP  pkg 0402LF  page 147 : A = P3V3_AUX ; B = GPU_HMC_PRSNT
R1872  Q_RES  10 1% CHIP  pkg 0402LF  page 202 : A = CLK_24M_66M_LPC0_ESPI ; B = ESPI_HOST_LPC_BMC_CLK

(kicad_pcb
	(version 20260206)
	(generator "pcbnew")
	(generator_version "10.0")
	(general
		(thickness 1.6)
		(legacy_teardrops no)
	)
	(paper "A4")
	(title_block
		(title "03242023_DA0F0TMBIJ0_F0T_Motherboard_J_brd_V01_OCP.brd")
		(comment 1 "Grand Teton / footprints 2246-2247 of 6105")
	)
	(layers
		(0 "F.Cu" signal "TOP")
		(4 "In1.Cu" signal "GND")
		(6 "In2.Cu" signal "IN1")
		(8 "In3.Cu" signal "GND1")
		(10 "In4.Cu" signal "IN2")
		(12 "In5.Cu" signal "GND2")
		(14 "In6.Cu" signal "IN3")
		(16 "In7.Cu" signal "GND3")
		(18 "In8.Cu" signal "VCC")
		(20 "In9.Cu" signal "VCC1")
		(22 "In10.Cu" signal "GND4")
		(24 "In11.Cu" signal "IN4")
		(26 "In12.Cu" signal "GND5")
		(28 "In13.Cu" signal "IN5")
		(30 "In14.Cu" signal "GND6")
		(32 "In15.Cu" signal "IN6")
		(34 "In16.Cu" signal "GND7")
		(2 "B.Cu" signal "BOTTOM")
		(9 "F.Adhes" user "F.Adhesive")
		(11 "B.Adhes" user "B.Adhesive")
		(13 "F.Paste" user "Package Geometry/Pastemask Top")
		(15 "B.Paste" user "Package Geometry/Pastemask Bottom")
		(5 "F.SilkS" user "Ref Des/Silkscreen Top")
		(7 "B.SilkS" user "Ref Des/Silkscreen Bottom")
		(1 "F.Mask" user "Board Geometry/Soldermask Top")
		(3 "B.Mask" user "Board Geometry/Soldermask Bottom")
		(17 "Dwgs.User" user "User.Drawings")
		(19 "Cmts.User" user "User.Comments")
		(21 "Eco1.User" user "User.Eco1")
		(23 "Eco2.User" user "User.Eco2")
		(25 "Edge.Cuts" user "Board Geometry/Outline")
		(27 "Margin" user)
		(31 "F.CrtYd" user "Package Geometry/Place Bound Top")
		(29 "B.CrtYd" user "Package Geometry/Place Bound Bottom")
		(35 "F.Fab" user "Ref Des/Assembly Top")
		(33 "B.Fab" user "Ref Des/Assembly Bottom")
	)
	(footprint ""
		(layer "F.Cu")
		(at 169.436288 -417.237418)
		(property "Reference" "R3434"
			(at 0 0 0)
			(layer "F.SilkS")
			(hide yes)
			(effects
				(font
					(size 1.27 1.27)
				)
			)
		)
		(property "Value" ""
			(at 0 0 0)
			(layer "F.Fab")
			(effects
				(font
					(size 1.27 1.27)
				)
			)
		)
		(duplicate_pad_numbers_are_jumpers no)
		(fp_line
			(start -0.7874 -0.4064)
			(end 0.7874 -0.4064)
			(stroke
				(width 0.1524)
				(type default)
			)
			(layer "F.SilkS")
		)
		(fp_line
			(start -0.7874 0.4064)
			(end -0.7874 -0.4064)
			(stroke
				(width 0.1524)
				(type default)
			)
			(layer "F.SilkS")
		)
		(fp_line
			(start 0.7874 -0.4064)
			(end 0.7874 0.4064)
			(stroke
				(width 0.1524)
				(type default)
			)
			(layer "F.SilkS")
		)
		(fp_line
			(start 0.7874 0.4064)
			(end -0.7874 0.4064)
			(stroke
				(width 0.1524)
				(type default)
			)
			(layer "F.SilkS")
		)
		(fp_line
			(start -0.67945 -0.305054)
			(end -0.12065 -0.305054)
			(stroke
				(width 0.1)
				(type default)
			)
			(layer "F.Fab")
		)
		(fp_line
			(start -0.67945 0.3048)
			(end -0.67945 -0.305054)
			(stroke
				(width 0.1)
				(type default)
			)
			(layer "F.Fab")
		)
		(fp_line
			(start -0.12065 -0.305054)
			(end -0.12065 -0.2794)
			(stroke
				(width 0.1)
				(type default)
			)
			(layer "F.Fab")
		)
		(fp_line
			(start -0.12065 -0.2794)
			(end 0.12065 -0.2794)
			(stroke
				(width 0.1)
				(type default)
			)
			(layer "F.Fab")
		)
		(fp_line
			(start -0.12065 0.2794)
			(end -0.12065 0.3048)
			(stroke
				(width 0.1)
				(type default)
			)
			(layer "F.Fab")
		)
		(fp_line
			(start -0.12065 0.3048)
			(end -0.67945 0.3048)
			(stroke
				(width 0.1)
				(type default)
			)
			(layer "F.Fab")
		)
		(fp_line
			(start 0.120396 0.2794)
			(end -0.12065 0.2794)
			(stroke
				(width 0.1)
				(type default)
			)
			(layer "F.Fab")
		)
		(fp_line
			(start 0.120396 0.3048)
			(end 0.120396 0.2794)
			(stroke
				(width 0.1)
				(type default)
			)
			(layer "F.Fab")
		)
		(fp_line
			(start 0.12065 -0.3048)
			(end 0.67945 -0.3048)
			(stroke
				(width 0.1)
				(type default)
			)
			(layer "F.Fab")
		)
		(fp_line
			(start 0.12065 -0.2794)
			(end 0.12065 -0.3048)
			(stroke
				(width 0.1)
				(type default)
			)
			(layer "F.Fab")
		)
		(fp_line
			(start 0.67945 -0.3048)
			(end 0.67945 0.3048)
			(stroke
				(width 0.1)
				(type default)
			)
			(layer "F.Fab")
		)
		(fp_line
			(start 0.67945 0.3048)
			(end 0.120396 0.3048)
			(stroke
				(width 0.1)
				(type default)
			)
			(layer "F.Fab")
		)
		(pad "1" smd circle
			(at -0.40005 0)
			(size 0 0)
			(layers "F.Cu" "F.Mask" "F.Paste")
			(net "P3V3_AUX")
		)
		(pad "2" smd circle
			(at 0.40005 0)
			(size 0 0)
			(layers "F.Cu" "F.Mask" "F.Paste")
			(net "GPU_HMC_PRSNT")
		)
	)
	(footprint ""
		(layer "F.Cu")
		(at 329.795378 -27.042618 -90)
		(property "Reference" "R1872"
			(at 0 0 270)
			(layer "F.SilkS")
			(hide yes)
			(effects
				(font
					(size 1.27 1.27)
				)
			)
		)
		(property "Value" ""
			(at 0 0 270)
			(layer "F.Fab")
			(effects
				(font
					(size 1.27 1.27)
				)
			)
		)
		(duplicate_pad_numbers_are_jumpers no)
		(fp_line
			(start -0.7874 0.4064)
			(end -0.7874 -0.4064)
			(stroke
				(width 0.1524)
				(type default)
			)
			(layer "F.SilkS")
		)
		(fp_line
			(start 0.7874 0.4064)
			(end -0.7874 0.4064)
			(stroke
				(width 0.1524)
				(type default)
			)
			(layer "F.SilkS")
		)
		(fp_line
			(start -0.7874 -0.4064)
			(end 0.7874 -0.4064)
			(stroke
				(width 0.1524)
				(type default)
			)
			(layer "F.SilkS")
		)
		(fp_line
			(start 0.7874 -0.4064)
			(end 0.7874 0.4064)
			(stroke
				(width 0.1524)
				(type default)
			)
			(layer "F.SilkS")
		)
		(fp_line
			(start -0.67945 0.3048)
			(end -0.67945 -0.305054)
			(stroke
				(width 0.1)
				(type default)
			)
			(layer "F.Fab")
		)
		(fp_line
			(start -0.12065 0.3048)
			(end -0.67945 0.3048)
			(stroke
				(width 0.1)
				(type default)
			)
			(layer "F.Fab")
		)
		(fp_line
			(start 0.120396 0.3048)
			(end 0.120396 0.2794)
			(stroke
				(width 0.1)
				(type default)
			)
			(layer "F.Fab")
		)
		(fp_line
			(start 0.67945 0.3048)
			(end 0.120396 0.3048)
			(stroke
				(width 0.1)
				(type default)
			)
			(layer "F.Fab")
		)
		(fp_line
			(start -0.12065 0.2794)
			(end -0.12065 0.3048)
			(stroke
				(width 0.1)
				(type default)
			)
			(layer "F.Fab")
		)
		(fp_line
			(start 0.120396 0.2794)
			(end -0.12065 0.2794)
			(stroke
				(width 0.1)
				(type default)
			)
			(layer "F.Fab")
		)
		(fp_line
			(start -0.12065 -0.2794)
			(end 0.12065 -0.2794)
			(stroke
				(width 0.1)
				(type default)
			)
			(layer "F.Fab")
		)
		(fp_line
			(start 0.12065 -0.2794)
			(end 0.12065 -0.3048)
			(stroke
				(width 0.1)
				(type default)
			)
			(layer "F.Fab")
		)
		(fp_line
			(start 0.12065 -0.3048)
			(end 0.67945 -0.3048)
			(stroke
				(width 0.1)
				(type default)
			)
			(layer "F.Fab")
		)
		(fp_line
			(start 0.67945 -0.3048)
			(end 0.67945 0.3048)
			(stroke
				(width 0.1)
				(type default)
			)
			(layer "F.Fab")
		)
		(fp_line
			(start -0.67945 -0.305054)
			(end -0.12065 -0.305054)
			(stroke
				(width 0.1)
				(type default)
			)
			(layer "F.Fab")
		)
		(fp_line
			(start -0.12065 -0.305054)
			(end -0.12065 -0.2794)
			(stroke
				(width 0.1)
				(type default)
			)
			(layer "F.Fab")
		)
		(pad "1" smd circle
			(at -0.40005 0 270)
			(size 0 0)
			(layers "F.Cu" "F.Mask" "F.Paste")
			(net "CLK_24M_66M_LPC0_ESPI")
		)
		(pad "2" smd circle
			(at 0.40005 0 270)
			(size 0 0)
			(layers "F.Cu" "F.Mask" "F.Paste")
			(net "ESPI_HOST_LPC_BMC_CLK")
		)
	)
)
